# S9S_MB_2U (Grand Teton) — schematic netlist excerpt (pin names and nets, part order shuffled) for the footprints in the layout excerpt that follows; sources: Cadence DE-HDL packaged netlist, KiCad conversion of 03242023_DA0F0TMBIJ0_F0T_Motherboard_J_brd_V01_OCP.brd

C248  Q_CAP  10UF 6.3V 20% X6S  pkg C0402  page 77 : A = PVCCIN_CPU1 ; B = GND
R3099  Q_RES  130 1% CHIP  pkg 0402LF  page 254 : A = LED_PWRGD_PVCCINFAON_CPU1 ; B = P3V3_AUX

(kicad_pcb
	(version 20260206)
	(generator "pcbnew")
	(generator_version "10.0")
	(general
		(thickness 1.6)
		(legacy_teardrops no)
	)
	(paper "A4")
	(title_block
		(title "03242023_DA0F0TMBIJ0_F0T_Motherboard_J_brd_V01_OCP.brd")
		(comment 1 "Grand Teton / footprints 32-33 of 6105")
	)
	(layers
		(0 "F.Cu" signal "TOP")
		(4 "In1.Cu" signal "GND")
		(6 "In2.Cu" signal "IN1")
		(8 "In3.Cu" signal "GND1")
		(10 "In4.Cu" signal "IN2")
		(12 "In5.Cu" signal "GND2")
		(14 "In6.Cu" signal "IN3")
		(16 "In7.Cu" signal "GND3")
		(18 "In8.Cu" signal "VCC")
		(20 "In9.Cu" signal "VCC1")
		(22 "In10.Cu" signal "GND4")
		(24 "In11.Cu" signal "IN4")
		(26 "In12.Cu" signal "GND5")
		(28 "In13.Cu" signal "IN5")
		(30 "In14.Cu" signal "GND6")
		(32 "In15.Cu" signal "IN6")
		(34 "In16.Cu" signal "GND7")
		(2 "B.Cu" signal "BOTTOM")
		(9 "F.Adhes" user "F.Adhesive")
		(11 "B.Adhes" user "B.Adhesive")
		(13 "F.Paste" user "Package Geometry/Pastemask Top")
		(15 "B.Paste" user "Package Geometry/Pastemask Bottom")
		(5 "F.SilkS" user "Ref Des/Silkscreen Top")
		(7 "B.SilkS" user "Ref Des/Silkscreen Bottom")
		(1 "F.Mask" user "Board Geometry/Soldermask Top")
		(3 "B.Mask" user "Board Geometry/Soldermask Bottom")
		(17 "Dwgs.User" user "User.Drawings")
		(19 "Cmts.User" user "User.Comments")
		(21 "Eco1.User" user "User.Eco1")
		(23 "Eco2.User" user "User.Eco2")
		(25 "Edge.Cuts" user "Board Geometry/Outline")
		(27 "Margin" user)
		(31 "F.CrtYd" user "Package Geometry/Place Bound Top")
		(29 "B.CrtYd" user "Package Geometry/Place Bound Bottom")
		(35 "F.Fab" user "Ref Des/Assembly Top")
		(33 "B.Fab" user "Ref Des/Assembly Bottom")
	)
	(footprint ""
		(layer "F.Cu")
		(at 109.695742 -65.22212 -90)
		(property "Reference" "R3099"
			(at 0 0 270)
			(layer "F.SilkS")
			(hide yes)
			(effects
				(font
					(size 1.27 1.27)
				)
			)
		)
		(property "Value" ""
			(at 0 0 270)
			(layer "F.Fab")
			(effects
				(font
					(size 1.27 1.27)
				)
			)
		)
		(duplicate_pad_numbers_are_jumpers no)
		(fp_line
			(start -0.7874 0.4064)
			(end -0.7874 -0.4064)
			(stroke
				(width 0.1524)
				(type default)
			)
			(layer "F.SilkS")
		)
		(fp_line
			(start 0.7874 0.4064)
			(end -0.7874 0.4064)
			(stroke
				(width 0.1524)
				(type default)
			)
			(layer "F.SilkS")
		)
		(fp_line
			(start -0.7874 -0.4064)
			(end 0.7874 -0.4064)
			(stroke
				(width 0.1524)
				(type default)
			)
			(layer "F.SilkS")
		)
		(fp_line
			(start 0.7874 -0.4064)
			(end 0.7874 0.4064)
			(stroke
				(width 0.1524)
				(type default)
			)
			(layer "F.SilkS")
		)
		(fp_line
			(start -0.67945 0.3048)
			(end -0.67945 -0.305054)
			(stroke
				(width 0.1)
				(type default)
			)
			(layer "F.Fab")
		)
		(fp_line
			(start -0.12065 0.3048)
			(end -0.67945 0.3048)
			(stroke
				(width 0.1)
				(type default)
			)
			(layer "F.Fab")
		)
		(fp_line
			(start 0.120396 0.3048)
			(end 0.120396 0.2794)
			(stroke
				(width 0.1)
				(type default)
			)
			(layer "F.Fab")
		)
		(fp_line
			(start 0.67945 0.3048)
			(end 0.120396 0.3048)
			(stroke
				(width 0.1)
				(type default)
			)
			(layer "F.Fab")
		)
		(fp_line
			(start -0.12065 0.2794)
			(end -0.12065 0.3048)
			(stroke
				(width 0.1)
				(type default)
			)
			(layer "F.Fab")
		)
		(fp_line
			(start 0.120396 0.2794)
			(end -0.12065 0.2794)
			(stroke
				(width 0.1)
				(type default)
			)
			(layer "F.Fab")
		)
		(fp_line
			(start -0.12065 -0.2794)
			(end 0.12065 -0.2794)
			(stroke
				(width 0.1)
				(type default)
			)
			(layer "F.Fab")
		)
		(fp_line
			(start 0.12065 -0.2794)
			(end 0.12065 -0.3048)
			(stroke
				(width 0.1)
				(type default)
			)
			(layer "F.Fab")
		)
		(fp_line
			(start 0.12065 -0.3048)
			(end 0.67945 -0.3048)
			(stroke
				(width 0.1)
				(type default)
			)
			(layer "F.Fab")
		)
		(fp_line
			(start 0.67945 -0.3048)
			(end 0.67945 0.3048)
			(stroke
				(width 0.1)
				(type default)
			)
			(layer "F.Fab")
		)
		(fp_line
			(start -0.67945 -0.305054)
			(end -0.12065 -0.305054)
			(stroke
				(width 0.1)
				(type default)
			)
			(layer "F.Fab")
		)
		(fp_line
			(start -0.12065 -0.305054)
			(end -0.12065 -0.2794)
			(stroke
				(width 0.1)
				(type default)
			)
			(layer "F.Fab")
		)
		(pad "1" smd circle
			(at -0.40005 0 270)
			(size 0 0)
			(layers "F.Cu" "F.Mask" "F.Paste")
			(net "LED_PWRGD_PVCCINFAON_CPU1")
		)
		(pad "2" smd circle
			(at 0.40005 0 270)
			(size 0 0)
			(layers "F.Cu" "F.Mask" "F.Paste")
			(net "P3V3_AUX")
		)
	)
	(footprint ""
		(layer "F.Cu")
		(at 118.542816 -256.6543 -90)
		(property "Reference" "C248"
			(at 0 0 270)
			(layer "F.SilkS")
			(hide yes)
			(effects
				(font
					(size 1.27 1.27)
				)
			)
		)
		(property "Value" ""
			(at 0 0 270)
			(layer "F.Fab")
			(effects
				(font
					(size 1.27 1.27)
				)
			)
		)
		(duplicate_pad_numbers_are_jumpers no)
		(fp_line
			(start -0.7874 0.4064)
			(end -0.7874 -0.4064)
			(stroke
				(width 0.1524)
				(type default)
			)
			(layer "F.SilkS")
		)
		(fp_line
			(start 0.7874 0.4064)
			(end -0.7874 0.4064)
			(stroke
				(width 0.1524)
				(type default)
			)
			(layer "F.SilkS")
		)
		(fp_line
			(start -0.7874 -0.4064)
			(end 0.7874 -0.4064)
			(stroke
				(width 0.1524)
				(type default)
			)
			(layer "F.SilkS")
		)
		(fp_line
			(start 0.7874 -0.4064)
			(end 0.7874 0.4064)
			(stroke
				(width 0.1524)
				(type default)
			)
			(layer "F.SilkS")
		)
		(fp_line
			(start -0.67945 0.3048)
			(end -0.67945 -0.305054)
			(stroke
				(width 0.1)
				(type default)
			)
			(layer "F.Fab")
		)
		(fp_line
			(start -0.12065 0.3048)
			(end -0.67945 0.3048)
			(stroke
				(width 0.1)
				(type default)
			)
			(layer "F.Fab")
		)
		(fp_line
			(start 0.120396 0.3048)
			(end 0.120396 0.2794)
			(stroke
				(width 0.1)
				(type default)
			)
			(layer "F.Fab")
		)
		(fp_line
			(start 0.67945 0.3048)
			(end 0.120396 0.3048)
			(stroke
				(width 0.1)
				(type default)
			)
			(layer "F.Fab")
		)
		(fp_line
			(start -0.12065 0.2794)
			(end -0.12065 0.3048)
			(stroke
				(width 0.1)
				(type default)
			)
			(layer "F.Fab")
		)
		(fp_line
			(start 0.120396 0.2794)
			(end -0.12065 0.2794)
			(stroke
				(width 0.1)
				(type default)
			)
			(layer "F.Fab")
		)
		(fp_line
			(start -0.12065 -0.2794)
			(end 0.12065 -0.2794)
			(stroke
				(width 0.1)
				(type default)
			)
			(layer "F.Fab")
		)
		(fp_line
			(start 0.12065 -0.2794)
			(end 0.12065 -0.3048)
			(stroke
				(width 0.1)
				(type default)
			)
			(layer "F.Fab")
		)
		(fp_line
			(start 0.12065 -0.3048)
			(end 0.67945 -0.3048)
			(stroke
				(width 0.1)
				(type default)
			)
			(layer "F.Fab")
		)
		(fp_line
			(start 0.67945 -0.3048)
			(end 0.67945 0.3048)
			(stroke
				(width 0.1)
				(type default)
			)
			(layer "F.Fab")
		)
		(fp_line
			(start -0.67945 -0.305054)
			(end -0.12065 -0.305054)
			(stroke
				(width 0.1)
				(type default)
			)
			(layer "F.Fab")
		)
		(fp_line
			(start -0.12065 -0.305054)
			(end -0.12065 -0.2794)
			(stroke
				(width 0.1)
				(type default)
			)
			(layer "F.Fab")
		)
		(pad "1" smd circle
			(at -0.40005 0 270)
			(size 0 0)
			(layers "F.Cu" "F.Mask" "F.Paste")
			(net "PVCCIN_CPU1")
		)
		(pad "2" smd circle
			(at 0.40005 0 270)
			(size 0 0)
			(layers "F.Cu" "F.Mask" "F.Paste")
			(net "GND")
		)
	)
)
